# S9S_MB_2U (Grand Teton) — schematic netlist excerpt (pin names and nets, part order shuffled) for the footprints in the layout excerpt that follows; sources: Cadence DE-HDL packaged netlist, KiCad conversion of 03242023_DA0F0TMBIJ0_F0T_Motherboard_J_brd_V01_OCP.brd

U95  74LVC1G07SE7  74LVC1G07SE-7 IC  pkg SOT353_0-65_2X1-25  page 244
  NC1  = NC
  A  = PWRGD_DSW_PWROK_R1
  GND  = GND
  Y  = PWRGD_DSW_PWROK_R2
  VCC  = P3V3_AUX

R311  Q_RES  0 5% CHIP  pkg 0402LF  page 284 : A = SVID_DIO0_CPU1_R ; B = SVID_DIO_PVCCIN_CPU1_R

(kicad_pcb
	(version 20260206)
	(generator "pcbnew")
	(generator_version "10.0")
	(general
		(thickness 1.6)
		(legacy_teardrops no)
	)
	(paper "A4")
	(title_block
		(title "03242023_DA0F0TMBIJ0_F0T_Motherboard_J_brd_V01_OCP.brd")
		(comment 1 "Grand Teton / footprints 504-505 of 6105")
	)
	(layers
		(0 "F.Cu" signal "TOP")
		(4 "In1.Cu" signal "GND")
		(6 "In2.Cu" signal "IN1")
		(8 "In3.Cu" signal "GND1")
		(10 "In4.Cu" signal "IN2")
		(12 "In5.Cu" signal "GND2")
		(14 "In6.Cu" signal "IN3")
		(16 "In7.Cu" signal "GND3")
		(18 "In8.Cu" signal "VCC")
		(20 "In9.Cu" signal "VCC1")
		(22 "In10.Cu" signal "GND4")
		(24 "In11.Cu" signal "IN4")
		(26 "In12.Cu" signal "GND5")
		(28 "In13.Cu" signal "IN5")
		(30 "In14.Cu" signal "GND6")
		(32 "In15.Cu" signal "IN6")
		(34 "In16.Cu" signal "GND7")
		(2 "B.Cu" signal "BOTTOM")
		(9 "F.Adhes" user "F.Adhesive")
		(11 "B.Adhes" user "B.Adhesive")
		(13 "F.Paste" user "Package Geometry/Pastemask Top")
		(15 "B.Paste" user "Package Geometry/Pastemask Bottom")
		(5 "F.SilkS" user "Ref Des/Silkscreen Top")
		(7 "B.SilkS" user "Ref Des/Silkscreen Bottom")
		(1 "F.Mask" user "Board Geometry/Soldermask Top")
		(3 "B.Mask" user "Board Geometry/Soldermask Bottom")
		(17 "Dwgs.User" user "User.Drawings")
		(19 "Cmts.User" user "User.Comments")
		(21 "Eco1.User" user "User.Eco1")
		(23 "Eco2.User" user "User.Eco2")
		(25 "Edge.Cuts" user "Board Geometry/Outline")
		(27 "Margin" user)
		(31 "F.CrtYd" user "Package Geometry/Place Bound Top")
		(29 "B.CrtYd" user "Package Geometry/Place Bound Bottom")
		(35 "F.Fab" user "Ref Des/Assembly Top")
		(33 "B.Fab" user "Ref Des/Assembly Bottom")
	)
	(footprint ""
		(layer "F.Cu")
		(at 213.93658 -127.782828 180)
		(property "Reference" "U95"
			(at -1.36144 -3.72491 0)
			(unlocked yes)
			(layer "F.SilkS")
			(effects
				(font
					(size 0.7874 0.5842)
					(thickness 0.1524)
				)
				(justify left)
			)
		)
		(property "Value" ""
			(at 0 0 180)
			(layer "F.Fab")
			(effects
				(font
					(size 1.27 1.27)
				)
			)
		)
		(duplicate_pad_numbers_are_jumpers no)
		(fp_line
			(start 1.400048 1.100074)
			(end -1.400048 1.100074)
			(stroke
				(width 0.1524)
				(type default)
			)
			(layer "F.SilkS")
		)
		(fp_line
			(start 1.400048 -1.100074)
			(end 1.400048 1.100074)
			(stroke
				(width 0.1524)
				(type default)
			)
			(layer "F.SilkS")
		)
		(fp_line
			(start 1.400048 -1.100074)
			(end -1.400048 -1.100074)
			(stroke
				(width 0.1524)
				(type default)
			)
			(layer "F.SilkS")
		)
		(fp_line
			(start -1.400048 1.100074)
			(end -1.400048 -1.100074)
			(stroke
				(width 0.1524)
				(type default)
			)
			(layer "F.SilkS")
		)
		(fp_poly
			(pts
				(xy -1.247394 -1.455928) (xy -1.755394 -2.471928) (xy -0.739394 -2.471928)
			)
			(stroke
				(width 0)
				(type default)
			)
			(fill yes)
			(layer "F.SilkS")
		)
		(fp_line
			(start 0.674878 1.100074)
			(end -0.674878 1.100074)
			(stroke
				(width 0.1)
				(type default)
			)
			(layer "F.Fab")
		)
		(fp_line
			(start 0.674878 -1.100074)
			(end 0.674878 1.100074)
			(stroke
				(width 0.1)
				(type default)
			)
			(layer "F.Fab")
		)
		(fp_line
			(start -0.674878 1.100074)
			(end -0.674878 -1.100074)
			(stroke
				(width 0.1)
				(type default)
			)
			(layer "F.Fab")
		)
		(fp_line
			(start -0.674878 -1.100074)
			(end 0.674878 -1.100074)
			(stroke
				(width 0.1)
				(type default)
			)
			(layer "F.Fab")
		)
		(fp_poly
			(pts
				(xy -1.590548 -0.649986) (xy -2.606548 -1.157986) (xy -2.606548 -0.141986)
			)
			(stroke
				(width 0)
				(type default)
			)
			(fill yes)
			(layer "F.Fab")
		)
		(pad "1" smd rect
			(at -0.94996 -0.649986 90)
			(size 0.4318 0.6096)
			(layers "F.Cu" "F.Mask" "F.Paste")
			(net "Net_1913")
		)
		(pad "2" smd rect
			(at -0.94996 0 90)
			(size 0.4318 0.6096)
			(layers "F.Cu" "F.Mask" "F.Paste")
			(net "PWRGD_DSW_PWROK_R1")
		)
		(pad "3" smd rect
			(at -0.94996 0.649986 90)
			(size 0.4318 0.6096)
			(layers "F.Cu" "F.Mask" "F.Paste")
			(net "GND")
		)
		(pad "4" smd rect
			(at 0.94996 0.649986 90)
			(size 0.4318 0.6096)
			(layers "F.Cu" "F.Mask" "F.Paste")
			(net "PWRGD_DSW_PWROK_R2")
		)
		(pad "5" smd rect
			(at 0.94996 -0.649986 90)
			(size 0.4318 0.6096)
			(layers "F.Cu" "F.Mask" "F.Paste")
			(net "P3V3_AUX")
		)
	)
	(footprint ""
		(layer "F.Cu")
		(at 102.845616 -356.668578)
		(property "Reference" "R311"
			(at 0 0 0)
			(layer "F.SilkS")
			(hide yes)
			(effects
				(font
					(size 1.27 1.27)
				)
			)
		)
		(property "Value" ""
			(at 0 0 0)
			(layer "F.Fab")
			(effects
				(font
					(size 1.27 1.27)
				)
			)
		)
		(duplicate_pad_numbers_are_jumpers no)
		(fp_line
			(start -0.7874 -0.4064)
			(end 0.7874 -0.4064)
			(stroke
				(width 0.1524)
				(type default)
			)
			(layer "F.SilkS")
		)
		(fp_line
			(start -0.7874 0.4064)
			(end -0.7874 -0.4064)
			(stroke
				(width 0.1524)
				(type default)
			)
			(layer "F.SilkS")
		)
		(fp_line
			(start 0.7874 -0.4064)
			(end 0.7874 0.4064)
			(stroke
				(width 0.1524)
				(type default)
			)
			(layer "F.SilkS")
		)
		(fp_line
			(start 0.7874 0.4064)
			(end -0.7874 0.4064)
			(stroke
				(width 0.1524)
				(type default)
			)
			(layer "F.SilkS")
		)
		(fp_line
			(start -0.67945 -0.305054)
			(end -0.12065 -0.305054)
			(stroke
				(width 0.1)
				(type default)
			)
			(layer "F.Fab")
		)
		(fp_line
			(start -0.67945 0.3048)
			(end -0.67945 -0.305054)
			(stroke
				(width 0.1)
				(type default)
			)
			(layer "F.Fab")
		)
		(fp_line
			(start -0.12065 -0.305054)
			(end -0.12065 -0.2794)
			(stroke
				(width 0.1)
				(type default)
			)
			(layer "F.Fab")
		)
		(fp_line
			(start -0.12065 -0.2794)
			(end 0.12065 -0.2794)
			(stroke
				(width 0.1)
				(type default)
			)
			(layer "F.Fab")
		)
		(fp_line
			(start -0.12065 0.2794)
			(end -0.12065 0.3048)
			(stroke
				(width 0.1)
				(type default)
			)
			(layer "F.Fab")
		)
		(fp_line
			(start -0.12065 0.3048)
			(end -0.67945 0.3048)
			(stroke
				(width 0.1)
				(type default)
			)
			(layer "F.Fab")
		)
		(fp_line
			(start 0.120396 0.2794)
			(end -0.12065 0.2794)
			(stroke
				(width 0.1)
				(type default)
			)
			(layer "F.Fab")
		)
		(fp_line
			(start 0.120396 0.3048)
			(end 0.120396 0.2794)
			(stroke
				(width 0.1)
				(type default)
			)
			(layer "F.Fab")
		)
		(fp_line
			(start 0.12065 -0.3048)
			(end 0.67945 -0.3048)
			(stroke
				(width 0.1)
				(type default)
			)
			(layer "F.Fab")
		)
		(fp_line
			(start 0.12065 -0.2794)
			(end 0.12065 -0.3048)
			(stroke
				(width 0.1)
				(type default)
			)
			(layer "F.Fab")
		)
		(fp_line
			(start 0.67945 -0.3048)
			(end 0.67945 0.3048)
			(stroke
				(width 0.1)
				(type default)
			)
			(layer "F.Fab")
		)
		(fp_line
			(start 0.67945 0.3048)
			(end 0.120396 0.3048)
			(stroke
				(width 0.1)
				(type default)
			)
			(layer "F.Fab")
		)
		(pad "1" smd circle
			(at -0.40005 0)
			(size 0 0)
			(layers "F.Cu" "F.Mask" "F.Paste")
			(net "SVID_DIO0_CPU1_R")
		)
		(pad "2" smd circle
			(at 0.40005 0)
			(size 0 0)
			(layers "F.Cu" "F.Mask" "F.Paste")
			(net "SVID_DIO_PVCCIN_CPU1_R")
		)
	)
)
